(kicad_pcb
	(version 20260206)
	(generator "pcbnew")
	(generator_version "10.0")
	(general
		(thickness 1.6)
		(legacy_teardrops no)
	)
	(paper "A4")
	(title_block
		(title "dpb — 14545-sa.0730WZS0815.brd")
		(comment 1 "Honey Badger (Wiwynn) / footprints 797-799 of 1066")
	)
	(layers
		(0 "F.Cu" signal "TOP")
		(4 "In1.Cu" signal "L2GND")
		(6 "In2.Cu" signal "L3")
		(8 "In3.Cu" signal "L4VCC")
		(10 "In4.Cu" signal "L5VCC")
		(12 "In5.Cu" signal "L6")
		(14 "In6.Cu" signal "L7GND")
		(2 "B.Cu" signal "BOTTOM")
		(9 "F.Adhes" user "F.Adhesive")
		(11 "B.Adhes" user "B.Adhesive")
		(13 "F.Paste" user "Package Geometry/Pastemask Top")
		(15 "B.Paste" user "Package Geometry/Pastemask Bottom")
		(5 "F.SilkS" user "Ref Des/Silkscreen Top")
		(7 "B.SilkS" user "Ref Des/Silkscreen Bottom")
		(1 "F.Mask" user "Board Geometry/Soldermask Top")
		(3 "B.Mask" user "Board Geometry/Soldermask Bottom")
		(17 "Dwgs.User" user "User.Drawings")
		(19 "Cmts.User" user "User.Comments")
		(21 "Eco1.User" user "User.Eco1")
		(23 "Eco2.User" user "User.Eco2")
		(25 "Edge.Cuts" user "Board Geometry/Outline")
		(27 "Margin" user)
		(31 "F.CrtYd" user "Package Geometry/Place Bound Top")
		(29 "B.CrtYd" user "Package Geometry/Place Bound Bottom")
		(35 "F.Fab" user "Ref Des/Assembly Top")
		(33 "B.Fab" user "Ref Des/Assembly Bottom")
	)
	(footprint ""
		(layer "F.Cu")
		(at 227.499926 -376.670062 90)
		(property "Reference" "SKT2"
			(at 0 0 90)
			(layer "F.SilkS")
			(hide yes)
			(effects
				(font
					(size 1.27 1.27)
				)
			)
		)
		(property "Value" "SKT-SATA14P-15P-12-GP"
			(at -22.6187 8.1788 90)
			(unlocked yes)
			(layer "F.Fab")
			(hide yes)
			(effects
				(font
					(size 1.016 1.016)
					(thickness 0.1524)
				)
			)
		)
		(property "Device Type" "87945-1001"
			(at -22.6187 6.6548 90)
			(unlocked yes)
			(layer "F.Fab")
			(hide yes)
			(effects
				(font
					(size 1.016 1.016)
					(thickness 0.1524)
				)
			)
		)
		(duplicate_pad_numbers_are_jumpers no)
		(fp_line
			(start -15.3924 -5.8547)
			(end -16.3576 -5.8547)
			(stroke
				(width 0.3302)
				(type default)
			)
			(layer "F.SilkS")
		)
		(fp_line
			(start 20.4724 -5.7658)
			(end 20.4724 -2.3114)
			(stroke
				(width 0.1524)
				(type default)
			)
			(layer "F.SilkS")
		)
		(fp_line
			(start -20.4724 -5.7658)
			(end 20.4724 -5.7658)
			(stroke
				(width 0.1524)
				(type default)
			)
			(layer "F.SilkS")
		)
		(fp_line
			(start 23.7617 -2.3114)
			(end 23.7617 2.3114)
			(stroke
				(width 0.1524)
				(type default)
			)
			(layer "F.SilkS")
		)
		(fp_line
			(start 20.4724 -2.3114)
			(end 23.7617 -2.3114)
			(stroke
				(width 0.1524)
				(type default)
			)
			(layer "F.SilkS")
		)
		(fp_line
			(start -20.4724 -2.3114)
			(end -20.4724 -5.7658)
			(stroke
				(width 0.1524)
				(type default)
			)
			(layer "F.SilkS")
		)
		(fp_line
			(start -23.7617 -2.3114)
			(end -20.4724 -2.3114)
			(stroke
				(width 0.1524)
				(type default)
			)
			(layer "F.SilkS")
		)
		(fp_line
			(start 23.117556 -0.5461)
			(end 23.117556 0.5461)
			(stroke
				(width 0.3048)
				(type default)
			)
			(layer "F.SilkS")
		)
		(fp_line
			(start -20.882356 -0.5461)
			(end -20.882356 0.5461)
			(stroke
				(width 0.3048)
				(type default)
			)
			(layer "F.SilkS")
		)
		(fp_line
			(start 20.882356 0.5461)
			(end 20.882356 -0.5461)
			(stroke
				(width 0.3048)
				(type default)
			)
			(layer "F.SilkS")
		)
		(fp_line
			(start -23.117556 0.5461)
			(end -23.117556 -0.5461)
			(stroke
				(width 0.3048)
				(type default)
			)
			(layer "F.SilkS")
		)
		(fp_line
			(start 23.7617 2.3114)
			(end 20.4724 2.3114)
			(stroke
				(width 0.1524)
				(type default)
			)
			(layer "F.SilkS")
		)
		(fp_line
			(start 20.4724 2.3114)
			(end 20.4724 9.652)
			(stroke
				(width 0.1524)
				(type default)
			)
			(layer "F.SilkS")
		)
		(fp_line
			(start -20.4724 2.3114)
			(end -23.7617 2.3114)
			(stroke
				(width 0.1524)
				(type default)
			)
			(layer "F.SilkS")
		)
		(fp_line
			(start -23.7617 2.3114)
			(end -23.7617 -2.3114)
			(stroke
				(width 0.1524)
				(type default)
			)
			(layer "F.SilkS")
		)
		(fp_line
			(start 17.8435 7.9502)
			(end -17.8435 7.9502)
			(stroke
				(width 0.1524)
				(type default)
			)
			(layer "F.SilkS")
		)
		(fp_line
			(start -17.8435 7.9502)
			(end -17.8435 9.652)
			(stroke
				(width 0.1524)
				(type default)
			)
			(layer "F.SilkS")
		)
		(fp_line
			(start 20.4724 9.652)
			(end 17.8435 9.652)
			(stroke
				(width 0.1524)
				(type default)
			)
			(layer "F.SilkS")
		)
		(fp_line
			(start 17.8435 9.652)
			(end 17.8435 7.9502)
			(stroke
				(width 0.1524)
				(type default)
			)
			(layer "F.SilkS")
		)
		(fp_line
			(start -17.8435 9.652)
			(end -20.4724 9.652)
			(stroke
				(width 0.1524)
				(type default)
			)
			(layer "F.SilkS")
		)
		(fp_line
			(start -20.4724 9.652)
			(end -20.4724 2.3114)
			(stroke
				(width 0.1524)
				(type default)
			)
			(layer "F.SilkS")
		)
		(fp_arc
			(start 20.882356 -0.5461)
			(mid 21.999956 -1.6637)
			(end 23.117556 -0.5461)
			(stroke
				(width 0.3048)
				(type default)
			)
			(layer "F.SilkS")
		)
		(fp_arc
			(start -23.117556 -0.5461)
			(mid -21.999956 -1.6637)
			(end -20.882356 -0.5461)
			(stroke
				(width 0.3048)
				(type default)
			)
			(layer "F.SilkS")
		)
		(fp_arc
			(start 23.117556 0.5461)
			(mid 21.999956 1.6637)
			(end 20.882356 0.5461)
			(stroke
				(width 0.3048)
				(type default)
			)
			(layer "F.SilkS")
		)
		(fp_arc
			(start -20.882356 0.5461)
			(mid -21.999956 1.6637)
			(end -23.117556 0.5461)
			(stroke
				(width 0.3048)
				(type default)
			)
			(layer "F.SilkS")
		)
		(fp_poly
			(pts
				(xy -15.87119 -5.838698) (xy -15.23619 -6.473698) (xy -16.50619 -6.473698)
			)
			(stroke
				(width 0)
				(type default)
			)
			(fill yes)
			(layer "F.SilkS")
		)
		(fp_poly
			(pts
				(xy -20.2184 -5.5118) (xy 20.2184 -5.5118) (xy 20.2184 -2.0574) (xy 23.5077 -2.0574) (xy 23.5077 2.0574)
				(xy 20.2184 2.0574) (xy 20.2184 9.398) (xy 18.0975 9.398) (xy 18.0975 7.6962) (xy -18.0975 7.6962)
				(xy -18.0975 9.398) (xy -20.2184 9.398) (xy -20.2184 2.0574) (xy -23.5077 2.0574) (xy -23.5077 -2.0574)
				(xy -20.2184 -2.0574)
			)
			(stroke
				(width 0)
				(type default)
			)
			(fill no)
			(layer "F.CrtYd")
		)
		(fp_poly
			(pts
				(xy -20.2184 -5.5118) (xy -20.2184 -6.0198) (xy -20.7264 -6.0198) (xy -20.7264 -2.5654) (xy -24.0157 -2.5654)
				(xy -24.0157 2.5654) (xy -20.7264 2.5654) (xy -20.7264 9.906) (xy -17.5895 9.906) (xy -17.5895 8.2042)
				(xy 17.5895 8.2042) (xy 17.5895 9.906) (xy 20.7264 9.906) (xy 20.7264 2.5654) (xy 24.0157 2.5654)
				(xy 24.0157 -2.5654) (xy 20.7264 -2.5654) (xy 20.7264 -6.0198) (xy -20.21586 -6.0198) (xy -20.21586 -5.5118)
				(xy 20.2184 -5.5118) (xy 20.2184 -2.0574) (xy 23.5077 -2.0574) (xy 23.5077 2.0574) (xy 20.2184 2.0574)
				(xy 20.2184 9.398) (xy 18.0975 9.398) (xy 18.0975 7.6962) (xy -18.0975 7.6962) (xy -18.0975 9.398)
				(xy -20.2184 9.398) (xy -20.2184 2.0574) (xy -23.5077 2.0574) (xy -23.5077 -2.0574) (xy -20.2184 -2.0574)
			)
			(stroke
				(width 0)
				(type default)
			)
			(fill no)
			(layer "F.CrtYd")
		)
		(fp_poly
			(pts
				(xy -20.7264 -6.0198) (xy -20.7264 -2.5654) (xy -24.0157 -2.5654) (xy -24.0157 2.5654) (xy -20.7264 2.5654)
				(xy -20.7264 9.906) (xy -17.5895 9.906) (xy -17.5895 8.2042) (xy 17.5895 8.2042) (xy 17.5895 9.906)
				(xy 20.7264 9.906) (xy 20.7264 2.5654) (xy 24.0157 2.5654) (xy 24.0157 -2.5654) (xy 20.7264 -2.5654)
				(xy 20.7264 -6.0198)
			)
			(stroke
				(width 0)
				(type default)
			)
			(fill no)
			(layer "F.Fab")
		)
		(pad "" np_thru_hole circle
			(at -18.999962 -2.350008 90)
			(size 0.254 0.254)
			(drill 1.8542)
			(layers "*.Cu" "*.Mask")
			(clearance 1.1557)
			(thermal_gap 1.1557)
		)
		(pad "" np_thru_hole circle
			(at 18.999962 -2.350008 90)
			(size 0.254 0.254)
			(drill 1.8542)
			(layers "*.Cu" "*.Mask")
			(clearance 1.1557)
			(thermal_gap 1.1557)
		)
		(pad "H1" thru_hole oval
			(at -21.999956 0 90)
			(size 1.524 2.6162)
			(drill oval 0.8128 1.905)
			(layers "*.Cu" "*.Mask")
			(remove_unused_layers no)
			(net "GND")
			(clearance 0.1524)
			(thermal_gap 0.1524)
		)
		(pad "H2" thru_hole oval
			(at 21.999956 0 90)
			(size 1.524 2.6162)
			(drill oval 0.8128 1.905)
			(layers "*.Cu" "*.Mask")
			(remove_unused_layers no)
			(net "GND")
			(clearance 0.1524)
			(thermal_gap 0.1524)
		)
		(pad "P1" smd rect
			(at -1.89992 -4.249928 90)
			(size 0.6604 2.3876)
			(layers "F.Cu" "F.Mask" "F.Paste")
			(net "Net_40")
		)
		(pad "P2" smd rect
			(at -0.62992 -4.249928 90)
			(size 0.6604 2.3876)
			(layers "F.Cu" "F.Mask" "F.Paste")
			(net "Net_39")
		)
		(pad "P3" smd rect
			(at 0.64008 -4.249928 90)
			(size 0.6604 2.3876)
			(layers "F.Cu" "F.Mask" "F.Paste")
			(net "Net_38")
		)
		(pad "P4" smd rect
			(at 1.91008 -4.249928 90)
			(size 0.6604 2.3876)
			(layers "F.Cu" "F.Mask" "F.Paste")
			(net "GND")
		)
		(pad "P5" smd rect
			(at 3.18008 -4.249928 90)
			(size 0.6604 2.3876)
			(layers "F.Cu" "F.Mask" "F.Paste")
			(net "HDD_PRSNT_NET1")
		)
		(pad "P6" smd rect
			(at 4.45008 -4.249928 90)
			(size 0.6604 2.3876)
			(layers "F.Cu" "F.Mask" "F.Paste")
			(net "GND")
		)
		(pad "P7" smd rect
			(at 5.72008 -4.249928 90)
			(size 0.6604 2.3876)
			(layers "F.Cu" "F.Mask" "F.Paste")
			(net "5V_PRE_1")
		)
		(pad "P8" smd rect
			(at 6.99008 -4.249928 90)
			(size 0.6604 2.3876)
			(layers "F.Cu" "F.Mask" "F.Paste")
			(net "P5V_HDD1")
		)
		(pad "P9" smd rect
			(at 8.26008 -4.249928 90)
			(size 0.6604 2.3876)
			(layers "F.Cu" "F.Mask" "F.Paste")
			(net "P5V_HDD1")
		)
		(pad "P10" smd rect
			(at 9.53008 -4.249928 90)
			(size 0.6604 2.3876)
			(layers "F.Cu" "F.Mask" "F.Paste")
			(net "GND")
		)
		(pad "P11" smd rect
			(at 10.80008 -4.249928 90)
			(size 0.6604 2.3876)
			(layers "F.Cu" "F.Mask" "F.Paste")
			(net "ACT_HDD1")
		)
		(pad "P12" smd rect
			(at 12.07008 -4.249928 90)
			(size 0.6604 2.3876)
			(layers "F.Cu" "F.Mask" "F.Paste")
			(net "GND")
		)
		(pad "P13" smd rect
			(at 13.34008 -4.249928 90)
			(size 0.6604 2.3876)
			(layers "F.Cu" "F.Mask" "F.Paste")
			(net "12V_PRE_1")
		)
		(pad "P14" smd rect
			(at 14.61008 -4.249928 90)
			(size 0.6604 2.3876)
			(layers "F.Cu" "F.Mask" "F.Paste")
			(net "P12V_HDD1")
		)
		(pad "P15" smd rect
			(at 15.88008 -4.249928 90)
			(size 0.6604 2.3876)
			(layers "F.Cu" "F.Mask" "F.Paste")
			(net "P12V_HDD1")
		)
		(pad "S1" smd rect
			(at -15.86992 -4.249928 90)
			(size 0.6604 2.3876)
			(layers "F.Cu" "F.Mask" "F.Paste")
			(net "GND")
		)
		(pad "S2" smd rect
			(at -14.59992 -4.249928 90)
			(size 0.6604 2.3876)
			(layers "F.Cu" "F.Mask" "F.Paste")
			(net "SAS2X28_A_HDD1_TX_+")
		)
		(pad "S3" smd rect
			(at -13.32992 -4.249928 90)
			(size 0.6604 2.3876)
			(layers "F.Cu" "F.Mask" "F.Paste")
			(net "SAS2X28_A_HDD1_TX_-")
		)
		(pad "S4" smd rect
			(at -12.05992 -4.249928 90)
			(size 0.6604 2.3876)
			(layers "F.Cu" "F.Mask" "F.Paste")
			(net "GND")
		)
		(pad "S5" smd rect
			(at -10.78992 -4.249928 90)
			(size 0.6604 2.3876)
			(layers "F.Cu" "F.Mask" "F.Paste")
			(net "SAS2X28_DRIVE_RX_N_A1")
		)
		(pad "S6" smd rect
			(at -9.51992 -4.249928 90)
			(size 0.6604 2.3876)
			(layers "F.Cu" "F.Mask" "F.Paste")
			(net "SAS2X28_DRIVE_RX_P_A1")
		)
		(pad "S7" smd rect
			(at -8.24992 -4.249928 90)
			(size 0.6604 2.3876)
			(layers "F.Cu" "F.Mask" "F.Paste")
			(net "GND")
		)
		(pad "S8" smd rect
			(at -7.480046 -2.100072 90)
			(size 0.508 1.905)
			(layers "F.Cu" "F.Mask" "F.Paste")
			(net "GND")
		)
		(pad "S9" smd rect
			(at -6.679946 -2.100072 90)
			(size 0.508 1.905)
			(layers "F.Cu" "F.Mask" "F.Paste")
			(net "SAS2X28_B_HDD1_TX_+")
		)
		(pad "S10" smd rect
			(at -5.8801 -2.100072 90)
			(size 0.508 1.905)
			(layers "F.Cu" "F.Mask" "F.Paste")
			(net "SAS2X28_B_HDD1_TX_-")
		)
		(pad "S11" smd rect
			(at -5.08 -2.100072 90)
			(size 0.508 1.905)
			(layers "F.Cu" "F.Mask" "F.Paste")
			(net "GND")
		)
		(pad "S12" smd rect
			(at -4.2799 -2.100072 90)
			(size 0.508 1.905)
			(layers "F.Cu" "F.Mask" "F.Paste")
			(net "SAS2X28_DRIVE_RX_N_B1")
		)
		(pad "S13" smd rect
			(at -3.480054 -2.100072 90)
			(size 0.508 1.905)
			(layers "F.Cu" "F.Mask" "F.Paste")
			(net "SAS2X28_DRIVE_RX_P_B1")
		)
		(pad "S14" smd rect
			(at -2.679954 -2.100072 90)
			(size 0.508 1.905)
			(layers "F.Cu" "F.Mask" "F.Paste")
			(net "GND")
		)
		(zone
			(layers "F.Cu" "B.Cu" "In1.Cu" "In2.Cu" "In3.Cu" "In4.Cu" "In5.Cu" "In6.Cu")
			(hatch none 0.5)
			(connect_pads
				(clearance 0)
			)
			(min_thickness 0.25)
			(keepout
				(tracks not_allowed)
				(vias allowed)
				(pads allowed)
				(copperpour not_allowed)
				(footprints allowed)
			)
			(placement
				(enabled no)
				(sheetname "")
			)
			(fill
				(thermal_gap 0.5)
				(thermal_bridge_width 0.5)
				(island_removal_mode 0)
			)
			(polygon
				(pts
					(arc
						(start 226.381818 -395.670024)
						(mid 223.918018 -395.670024)
						(end 226.381818 -395.670024)
					)
				)
			)
		)
		(zone
			(layers "F.Cu" "B.Cu" "In1.Cu" "In2.Cu" "In3.Cu" "In4.Cu" "In5.Cu" "In6.Cu")
			(hatch none 0.5)
			(connect_pads
				(clearance 0)
			)
			(min_thickness 0.25)
			(keepout
				(tracks not_allowed)
				(vias allowed)
				(pads allowed)
				(copperpour not_allowed)
				(footprints allowed)
			)
			(placement
				(enabled no)
				(sheetname "")
			)
			(fill
				(thermal_gap 0.5)
				(thermal_bridge_width 0.5)
				(island_removal_mode 0)
			)
			(polygon
				(pts
					(arc
						(start 226.381818 -357.6701)
						(mid 223.918018 -357.6701)
						(end 226.381818 -357.6701)
					)
				)
			)
		)
	)
	(footprint ""
		(layer "F.Cu")
		(at 50.546 -416.433 180)
		(property "Reference" "C389"
			(at 0 0 180)
			(layer "F.SilkS")
			(hide yes)
			(effects
				(font
					(size 1.27 1.27)
				)
			)
		)
		(property "Value" "SCD033U25V2KX-GP"
			(at 1.1811 -2.7051 180)
			(unlocked yes)
			(layer "F.Fab")
			(hide yes)
			(effects
				(font
					(size 1.016 1.016)
					(thickness 0.1524)
				)
			)
		)
		(property "Device Type" "C402H22"
			(at 1.1811 -4.2291 180)
			(unlocked yes)
			(layer "F.Fab")
			(hide yes)
			(effects
				(font
					(size 1.016 1.016)
					(thickness 0.1524)
				)
			)
		)
		(duplicate_pad_numbers_are_jumpers no)
		(fp_rect
			(start -0.4318 0.9525)
			(end 0.4318 -0.9525)
			(stroke
				(width 0)
				(type default)
			)
			(fill no)
			(layer "F.CrtYd")
		)
		(fp_rect
			(start -0.4318 0.9525)
			(end 0.4318 -0.9525)
			(stroke
				(width 0)
				(type default)
			)
			(fill no)
			(layer "F.Fab")
		)
		(pad "1" smd custom
			(at 0 -0.4445 180)
			(size 0.1524 0.1524)
			(layers "F.Cu" "F.Mask" "F.Paste")
			(net "P12V")
			(options
				(clearance outline)
				(anchor circle)
			)
			(primitives
				(gr_poly
					(pts
						(arc
							(start 0.3048 -0.2032)
							(mid 0.275042 -0.275042)
							(end 0.2032 -0.3048)
						)
						(arc
							(start -0.2032 -0.3048)
							(mid -0.275042 -0.275042)
							(end -0.3048 -0.2032)
						)
						(arc
							(start -0.3048 0.2032)
							(mid -0.275042 0.275042)
							(end -0.2032 0.3048)
						)
						(arc
							(start 0.2032 0.3048)
							(mid 0.275042 0.275042)
							(end 0.3048 0.2032)
						)
					)
					(width 0)
					(fill yes)
				)
			)
		)
		(pad "2" smd custom
			(at 0 0.4445 180)
			(size 0.1524 0.1524)
			(layers "F.Cu" "F.Mask" "F.Paste")
			(net "SW_HDD10_N")
			(options
				(clearance outline)
				(anchor circle)
			)
			(primitives
				(gr_poly
					(pts
						(arc
							(start 0.3048 -0.2032)
							(mid 0.275042 -0.275042)
							(end 0.2032 -0.3048)
						)
						(arc
							(start -0.2032 -0.3048)
							(mid -0.275042 -0.275042)
							(end -0.3048 -0.2032)
						)
						(arc
							(start -0.3048 0.2032)
							(mid -0.275042 0.275042)
							(end -0.2032 0.3048)
						)
						(arc
							(start 0.2032 0.3048)
							(mid 0.275042 0.275042)
							(end 0.3048 0.2032)
						)
					)
					(width 0)
					(fill yes)
				)
			)
		)
	)
	(footprint ""
		(layer "F.Cu")
		(at 59.816746 -21.0947)
		(property "Reference" "PC17"
			(at 0 0 0)
			(layer "F.SilkS")
			(hide yes)
			(effects
				(font
					(size 1.27 1.27)
				)
			)
		)
		(property "Value" "SC1U10V2KX-1GP"
			(at 1.1811 -2.7051 0)
			(unlocked yes)
			(layer "F.Fab")
			(hide yes)
			(effects
				(font
					(size 1.016 1.016)
					(thickness 0.1524)
				)
			)
		)
		(property "Device Type" "C402H22"
			(at 1.1811 -4.2291 0)
			(unlocked yes)
			(layer "F.Fab")
			(hide yes)
			(effects
				(font
					(size 1.016 1.016)
					(thickness 0.1524)
				)
			)
		)
		(duplicate_pad_numbers_are_jumpers no)
		(fp_rect
			(start -0.4318 0.9525)
			(end 0.4318 -0.9525)
			(stroke
				(width 0)
				(type default)
			)
			(fill no)
			(layer "F.CrtYd")
		)
		(fp_rect
			(start -0.4318 0.9525)
			(end 0.4318 -0.9525)
			(stroke
				(width 0)
				(type default)
			)
			(fill no)
			(layer "F.Fab")
		)
		(pad "1" smd custom
			(at 0 -0.4445)
			(size 0.1524 0.1524)
			(layers "F.Cu" "F.Mask" "F.Paste")
			(net "P5VB_VREG")
			(options
				(clearance outline)
				(anchor circle)
			)
			(primitives
				(gr_poly
					(pts
						(arc
							(start 0.3048 -0.2032)
							(mid 0.275042 -0.275042)
							(end 0.2032 -0.3048)
						)
						(arc
							(start -0.2032 -0.3048)
							(mid -0.275042 -0.275042)
							(end -0.3048 -0.2032)
						)
						(arc
							(start -0.3048 0.2032)
							(mid -0.275042 0.275042)
							(end -0.2032 0.3048)
						)
						(arc
							(start 0.2032 0.3048)
							(mid 0.275042 0.275042)
							(end 0.3048 0.2032)
						)
					)
					(width 0)
					(fill yes)
				)
			)
		)
		(pad "2" smd custom
			(at 0 0.4445)
			(size 0.1524 0.1524)
			(layers "F.Cu" "F.Mask" "F.Paste")
			(net "GND")
			(options
				(clearance outline)
				(anchor circle)
			)
			(primitives
				(gr_poly
					(pts
						(arc
							(start 0.3048 -0.2032)
							(mid 0.275042 -0.275042)
							(end 0.2032 -0.3048)
						)
						(arc
							(start -0.2032 -0.3048)
							(mid -0.275042 -0.275042)
							(end -0.3048 -0.2032)
						)
						(arc
							(start -0.3048 0.2032)
							(mid -0.275042 0.275042)
							(end -0.2032 0.3048)
						)
						(arc
							(start 0.2032 0.3048)
							(mid 0.275042 0.275042)
							(end 0.3048 0.2032)
						)
					)
					(width 0)
					(fill yes)
				)
			)
		)
	)
)
